(kicad_pcb
	(version 20260206)
	(generator "pcbnew")
	(generator_version "10.0")
	(general
		(thickness 1.6)
		(legacy_teardrops no)
	)
	(paper "A4")
	(title_block
		(title "Wiwynn_Tioga_Pass_MB.brd")
		(comment 1 "Tioga Pass / footprint 2838 of 4770 (J6U2), pads 244-291 of 291")
	)
	(layers
		(0 "F.Cu" signal "TOP")
		(4 "In1.Cu" signal "L2GND")
		(6 "In2.Cu" signal "L3")
		(8 "In3.Cu" signal "L4GND")
		(10 "In4.Cu" signal "L5")
		(12 "In5.Cu" signal "L6GND")
		(14 "In6.Cu" signal "L7VCC")
		(16 "In7.Cu" signal "L8VCC")
		(18 "In8.Cu" signal "L9GND")
		(20 "In9.Cu" signal "L10")
		(22 "In10.Cu" signal "L11GND")
		(24 "In11.Cu" signal "L12")
		(26 "In12.Cu" signal "L13GND")
		(2 "B.Cu" signal "BOTTOM")
		(9 "F.Adhes" user "F.Adhesive")
		(11 "B.Adhes" user "B.Adhesive")
		(13 "F.Paste" user "Package Geometry/Pastemask Top")
		(15 "B.Paste" user "Package Geometry/Pastemask Bottom")
		(5 "F.SilkS" user "Ref Des/Silkscreen Top")
		(7 "B.SilkS" user "Ref Des/Silkscreen Bottom")
		(1 "F.Mask" user "Board Geometry/Soldermask Top")
		(3 "B.Mask" user "Board Geometry/Soldermask Bottom")
		(17 "Dwgs.User" user "User.Drawings")
		(19 "Cmts.User" user "User.Comments")
		(21 "Eco1.User" user "User.Eco1")
		(23 "Eco2.User" user "User.Eco2")
		(25 "Edge.Cuts" user "Board Geometry/Outline")
		(27 "Margin" user)
		(31 "F.CrtYd" user "Package Geometry/Place Bound Top")
		(29 "B.CrtYd" user "Package Geometry/Place Bound Bottom")
		(35 "F.Fab" user "Ref Des/Assembly Top")
		(33 "B.Fab" user "Ref Des/Assembly Bottom")
	)
	(footprint ""
		(layer "B.Cu")
		(at 194.700398 -5.621782 90)
		(property "Reference" "J6U2"
			(at 2.225548 39.48811 0)
			(unlocked yes)
			(layer "B.SilkS")
			(effects
				(font
					(size 0.7874 0.5842)
					(thickness 0.1524)
				)
				(justify left mirror)
			)
		)
		(property "Value" ""
			(at 0 0 90)
			(layer "B.Fab")
			(effects
				(font
					(size 1.27 1.27)
				)
				(justify mirror)
			)
		)
		(duplicate_pad_numbers_are_jumpers no)
		(pad "241" smd rect
			(at -4.59994 86.700106 270)
			(size 1.8034 0.508)
			(layers "B.Cu" "B.Mask" "B.Paste")
			(net "GND")
		)
		(pad "242" smd rect
			(at -4.59994 87.54999 270)
			(size 1.8034 0.508)
			(layers "B.Cu" "B.Mask" "B.Paste")
			(net "M_C_DQ<33>")
		)
		(pad "243" smd rect
			(at -4.59994 88.399874 270)
			(size 1.8034 0.508)
			(layers "B.Cu" "B.Mask" "B.Paste")
			(net "GND")
		)
		(pad "244" smd rect
			(at -4.59994 89.250012 270)
			(size 1.8034 0.508)
			(layers "B.Cu" "B.Mask" "B.Paste")
			(net "M_C_DQS_DN<4>")
		)
		(pad "245" smd rect
			(at -4.59994 90.099896 270)
			(size 1.8034 0.508)
			(layers "B.Cu" "B.Mask" "B.Paste")
			(net "M_C_DQS_DP<4>")
		)
		(pad "246" smd rect
			(at -4.59994 90.950034 270)
			(size 1.8034 0.508)
			(layers "B.Cu" "B.Mask" "B.Paste")
			(net "GND")
		)
		(pad "247" smd rect
			(at -4.59994 91.799918 270)
			(size 1.8034 0.508)
			(layers "B.Cu" "B.Mask" "B.Paste")
			(net "M_C_DQ<39>")
		)
		(pad "248" smd rect
			(at -4.59994 92.650056 270)
			(size 1.8034 0.508)
			(layers "B.Cu" "B.Mask" "B.Paste")
			(net "GND")
		)
		(pad "249" smd rect
			(at -4.59994 93.49994 270)
			(size 1.8034 0.508)
			(layers "B.Cu" "B.Mask" "B.Paste")
			(net "M_C_DQ<35>")
		)
		(pad "250" smd rect
			(at -4.59994 94.350078 270)
			(size 1.8034 0.508)
			(layers "B.Cu" "B.Mask" "B.Paste")
			(net "GND")
		)
		(pad "251" smd rect
			(at -4.59994 95.199962 270)
			(size 1.8034 0.508)
			(layers "B.Cu" "B.Mask" "B.Paste")
			(net "M_C_DQ<45>")
		)
		(pad "252" smd rect
			(at -4.59994 96.0501 270)
			(size 1.8034 0.508)
			(layers "B.Cu" "B.Mask" "B.Paste")
			(net "GND")
		)
		(pad "253" smd rect
			(at -4.59994 96.899984 270)
			(size 1.8034 0.508)
			(layers "B.Cu" "B.Mask" "B.Paste")
			(net "M_C_DQ<41>")
		)
		(pad "254" smd rect
			(at -4.59994 97.750122 270)
			(size 1.8034 0.508)
			(layers "B.Cu" "B.Mask" "B.Paste")
			(net "GND")
		)
		(pad "255" smd rect
			(at -4.59994 98.600006 270)
			(size 1.8034 0.508)
			(layers "B.Cu" "B.Mask" "B.Paste")
			(net "M_C_DQS_DN<5>")
		)
		(pad "256" smd rect
			(at -4.59994 99.44989 270)
			(size 1.8034 0.508)
			(layers "B.Cu" "B.Mask" "B.Paste")
			(net "M_C_DQS_DP<5>")
		)
		(pad "257" smd rect
			(at -4.59994 100.300028 270)
			(size 1.8034 0.508)
			(layers "B.Cu" "B.Mask" "B.Paste")
			(net "GND")
		)
		(pad "258" smd rect
			(at -4.59994 101.149912 270)
			(size 1.8034 0.508)
			(layers "B.Cu" "B.Mask" "B.Paste")
			(net "M_C_DQ<47>")
		)
		(pad "259" smd rect
			(at -4.59994 102.00005 270)
			(size 1.8034 0.508)
			(layers "B.Cu" "B.Mask" "B.Paste")
			(net "GND")
		)
		(pad "260" smd rect
			(at -4.59994 102.849934 270)
			(size 1.8034 0.508)
			(layers "B.Cu" "B.Mask" "B.Paste")
			(net "M_C_DQ<43>")
		)
		(pad "261" smd rect
			(at -4.59994 103.700072 270)
			(size 1.8034 0.508)
			(layers "B.Cu" "B.Mask" "B.Paste")
			(net "GND")
		)
		(pad "262" smd rect
			(at -4.59994 104.549956 270)
			(size 1.8034 0.508)
			(layers "B.Cu" "B.Mask" "B.Paste")
			(net "M_C_DQ<53>")
		)
		(pad "263" smd rect
			(at -4.59994 105.400094 270)
			(size 1.8034 0.508)
			(layers "B.Cu" "B.Mask" "B.Paste")
			(net "GND")
		)
		(pad "264" smd rect
			(at -4.59994 106.249978 270)
			(size 1.8034 0.508)
			(layers "B.Cu" "B.Mask" "B.Paste")
			(net "M_C_DQ<49>")
		)
		(pad "265" smd rect
			(at -4.59994 107.100116 270)
			(size 1.8034 0.508)
			(layers "B.Cu" "B.Mask" "B.Paste")
			(net "GND")
		)
		(pad "266" smd rect
			(at -4.59994 107.95 270)
			(size 1.8034 0.508)
			(layers "B.Cu" "B.Mask" "B.Paste")
			(net "M_C_DQS_DN<6>")
		)
		(pad "267" smd rect
			(at -4.59994 108.799884 270)
			(size 1.8034 0.508)
			(layers "B.Cu" "B.Mask" "B.Paste")
			(net "M_C_DQS_DP<6>")
		)
		(pad "268" smd rect
			(at -4.59994 109.650022 270)
			(size 1.8034 0.508)
			(layers "B.Cu" "B.Mask" "B.Paste")
			(net "GND")
		)
		(pad "269" smd rect
			(at -4.59994 110.499906 270)
			(size 1.8034 0.508)
			(layers "B.Cu" "B.Mask" "B.Paste")
			(net "M_C_DQ<55>")
		)
		(pad "270" smd rect
			(at -4.59994 111.350044 270)
			(size 1.8034 0.508)
			(layers "B.Cu" "B.Mask" "B.Paste")
			(net "GND")
		)
		(pad "271" smd rect
			(at -4.59994 112.199928 270)
			(size 1.8034 0.508)
			(layers "B.Cu" "B.Mask" "B.Paste")
			(net "M_C_DQ<51>")
		)
		(pad "272" smd rect
			(at -4.59994 113.050066 270)
			(size 1.8034 0.508)
			(layers "B.Cu" "B.Mask" "B.Paste")
			(net "GND")
		)
		(pad "273" smd rect
			(at -4.59994 113.89995 270)
			(size 1.8034 0.508)
			(layers "B.Cu" "B.Mask" "B.Paste")
			(net "M_C_DQ<61>")
		)
		(pad "274" smd rect
			(at -4.59994 114.750088 270)
			(size 1.8034 0.508)
			(layers "B.Cu" "B.Mask" "B.Paste")
			(net "GND")
		)
		(pad "275" smd rect
			(at -4.59994 115.599972 270)
			(size 1.8034 0.508)
			(layers "B.Cu" "B.Mask" "B.Paste")
			(net "M_C_DQ<57>")
		)
		(pad "276" smd rect
			(at -4.59994 116.45011 270)
			(size 1.8034 0.508)
			(layers "B.Cu" "B.Mask" "B.Paste")
			(net "GND")
		)
		(pad "277" smd rect
			(at -4.59994 117.299994 270)
			(size 1.8034 0.508)
			(layers "B.Cu" "B.Mask" "B.Paste")
			(net "M_C_DQS_DN<7>")
		)
		(pad "278" smd rect
			(at -4.59994 118.149878 270)
			(size 1.8034 0.508)
			(layers "B.Cu" "B.Mask" "B.Paste")
			(net "M_C_DQS_DP<7>")
		)
		(pad "279" smd rect
			(at -4.59994 119.000016 270)
			(size 1.8034 0.508)
			(layers "B.Cu" "B.Mask" "B.Paste")
			(net "GND")
		)
		(pad "280" smd rect
			(at -4.59994 119.8499 270)
			(size 1.8034 0.508)
			(layers "B.Cu" "B.Mask" "B.Paste")
			(net "M_C_DQ<63>")
		)
		(pad "281" smd rect
			(at -4.59994 120.700038 270)
			(size 1.8034 0.508)
			(layers "B.Cu" "B.Mask" "B.Paste")
			(net "GND")
		)
		(pad "282" smd rect
			(at -4.59994 121.549922 270)
			(size 1.8034 0.508)
			(layers "B.Cu" "B.Mask" "B.Paste")
			(net "M_C_DQ<59>")
		)
		(pad "283" smd rect
			(at -4.59994 122.40006 270)
			(size 1.8034 0.508)
			(layers "B.Cu" "B.Mask" "B.Paste")
			(net "GND")
		)
		(pad "284" smd rect
			(at -4.59994 123.249944 270)
			(size 1.8034 0.508)
			(layers "B.Cu" "B.Mask" "B.Paste")
			(net "PVPP_ABC")
		)
		(pad "285" smd rect
			(at -4.59994 124.100082 270)
			(size 1.8034 0.508)
			(layers "B.Cu" "B.Mask" "B.Paste")
			(net "SMB_DDR_ABC_VPP_SDA")
		)
		(pad "286" smd rect
			(at -4.59994 124.949966 270)
			(size 1.8034 0.508)
			(layers "B.Cu" "B.Mask" "B.Paste")
			(net "PVPP_ABC")
		)
		(pad "287" smd rect
			(at -4.59994 125.800104 270)
			(size 1.8034 0.508)
			(layers "B.Cu" "B.Mask" "B.Paste")
			(net "PVPP_ABC")
		)
		(pad "288" smd rect
			(at -4.59994 126.649988 270)
			(size 1.8034 0.508)
			(layers "B.Cu" "B.Mask" "B.Paste")
			(net "PVPP_ABC")
		)
	)
)
